(kicad_pcb
	(version 20241229)
	(generator "pcbnew")
	(generator_version "9.0")
	(general
		(thickness 1.6)
		(legacy_teardrops no)
	)
	(paper "A4")
	(title_block
		(title "GMSL Deserializer")
		(date "2025-10-09")
		(rev "1.0.4")
		(company "Antmicro Ltd")
		(comment 1 "www.antmicro.com")
		(comment 9 "footprints 39-43 of 235")
	)
	(layers
		(0 "F.Cu" signal)
		(4 "In1.Cu" power)
		(6 "In2.Cu" power)
		(2 "B.Cu" signal)
		(9 "F.Adhes" user "F.Adhesive")
		(11 "B.Adhes" user "B.Adhesive")
		(13 "F.Paste" user)
		(15 "B.Paste" user)
		(5 "F.SilkS" user "F.Silkscreen")
		(7 "B.SilkS" user "B.Silkscreen")
		(1 "F.Mask" user)
		(3 "B.Mask" user)
		(17 "Dwgs.User" user "User.Drawings")
		(19 "Cmts.User" user "User.Comments")
		(21 "Eco1.User" user "User.Eco1")
		(23 "Eco2.User" user "User.Eco2")
		(25 "Edge.Cuts" user)
		(27 "Margin" user)
		(31 "F.CrtYd" user "F.Courtyard")
		(29 "B.CrtYd" user "B.Courtyard")
		(35 "F.Fab" user)
		(33 "B.Fab" user)
	)
	(footprint "antmicro-footprints:D_SOD-323F"
		(layer "F.Cu")
		(at 126.166 78.844 90)
		(property "Reference" "D3"
			(at -1.293 -1.198 90)
			(layer "F.SilkS")
			(effects
				(font
					(size 0.7 0.7)
					(thickness 0.15)
				)
				(justify left bottom)
			)
		)
		(property "Value" "PMEG3010CEJ,115"
			(at -1.7 1.899 90)
			(layer "F.Fab")
			(effects
				(font
					(size 0.7 0.7)
					(thickness 0.15)
				)
				(justify left bottom)
			)
		)
		(property "Datasheet" "https://assets.nexperia.com/documents/data-sheet/PMEG3010CEH_PMEG3010CEJ.pdf"
			(at 0 0 90)
			(layer "F.Fab")
			(hide yes)
			(effects
				(font
					(size 1.27 1.27)
					(thickness 0.15)
				)
			)
		)
		(property "Description" "Schottky Rectifier, 30 V, 1 A, Single, SOD-323F, 2 Pins, 520 mV"
			(at 0 0 90)
			(layer "F.Fab")
			(hide yes)
			(effects
				(font
					(size 1.27 1.27)
					(thickness 0.15)
				)
			)
		)
		(property "Author" "Antmicro"
			(at 205.01 -47.322 0)
			(layer "F.Fab")
			(hide yes)
			(effects
				(font
					(size 1 1)
					(thickness 0.15)
				)
			)
		)
		(property "License" "Apache-2.0"
			(at 205.01 -47.322 0)
			(layer "F.Fab")
			(hide yes)
			(effects
				(font
					(size 1 1)
					(thickness 0.15)
				)
			)
		)
		(property "MPN" "PMEG3010CEJ,115"
			(at 205.01 -47.322 0)
			(layer "F.Fab")
			(hide yes)
			(effects
				(font
					(size 1 1)
					(thickness 0.15)
				)
			)
		)
		(property "Manufacturer" "Nexperia"
			(at 205.01 -47.322 0)
			(layer "F.Fab")
			(hide yes)
			(effects
				(font
					(size 1 1)
					(thickness 0.15)
				)
			)
		)
		(property "Public" ""
			(at 205.01 -47.322 0)
			(layer "F.Fab")
			(hide yes)
			(effects
				(font
					(size 1 1)
					(thickness 0.15)
				)
			)
		)
		(sheetname "/Power/")
		(sheetfile "power.kicad_sch")
		(attr smd)
		(fp_line
			(start 0.973 -0.749)
			(end 0.973 -0.449)
			(stroke
				(width 0.15)
				(type solid)
			)
			(layer "F.SilkS")
		)
		(fp_line
			(start 0.623 -0.749)
			(end 0.973 -0.749)
			(stroke
				(width 0.15)
				(type solid)
			)
			(layer "F.SilkS")
		)
		(fp_line
			(start -0.625 -0.749)
			(end -0.975 -0.749)
			(stroke
				(width 0.15)
				(type solid)
			)
			(layer "F.SilkS")
		)
		(fp_line
			(start -0.975 -0.749)
			(end -0.975 -0.449)
			(stroke
				(width 0.15)
				(type solid)
			)
			(layer "F.SilkS")
		)
		(fp_line
			(start -0.5 -0.425)
			(end -0.5 0.425)
			(stroke
				(width 0.15)
				(type solid)
			)
			(layer "F.SilkS")
		)
		(fp_line
			(start 0.973 0.451)
			(end 0.973 0.749)
			(stroke
				(width 0.15)
				(type solid)
			)
			(layer "F.SilkS")
		)
		(fp_line
			(start 0.973 0.749)
			(end 0.623 0.749)
			(stroke
				(width 0.15)
				(type solid)
			)
			(layer "F.SilkS")
		)
		(fp_line
			(start -0.625 0.749)
			(end -0.975 0.749)
			(stroke
				(width 0.15)
				(type solid)
			)
			(layer "F.SilkS")
		)
		(fp_line
			(start -0.975 0.749)
			(end -0.975 0.451)
			(stroke
				(width 0.15)
				(type solid)
			)
			(layer "F.SilkS")
		)
		(fp_rect
			(start -1.55 -0.95)
			(end 1.55 0.95)
			(stroke
				(width 0.05)
				(type solid)
			)
			(fill no)
			(layer "F.CrtYd")
		)
		(fp_rect
			(start -1.25 -0.676)
			(end 1.245365 0.676)
			(stroke
				(width 0.1)
				(type solid)
			)
			(fill no)
			(layer "F.Fab")
		)
		(pad "1" smd roundrect
			(at -1.051 0.001 90)
			(size 0.8 0.6)
			(layers "F.Cu" "F.Mask" "F.Paste")
			(roundrect_rratio 0.15)
			(net 123 "/Power/OUT_12V")
			(pinfunction "C")
			(pintype "passive")
		)
		(pad "2" smd roundrect
			(at 1.05 0.001 90)
			(size 0.8 0.6)
			(layers "F.Cu" "F.Mask" "F.Paste")
			(roundrect_rratio 0.15)
			(net 124 "/Power/SW_12V")
			(pinfunction "A")
			(pintype "passive")
		)
	)
	(footprint "antmicro-footprints:L_Coilcraft-1210POC"
		(layer "F.Cu")
		(at 136.906 56.642 90)
		(property "Reference" "L6"
			(at -0.635 -1.778 90)
			(layer "F.SilkS")
			(effects
				(font
					(size 0.7 0.7)
					(thickness 0.15)
				)
				(justify left bottom)
			)
		)
		(property "Value" "L_6u8_1A_Coilcraft-1210POC"
			(at 0 2.4 90)
			(layer "F.Fab")
			(effects
				(font
					(size 0.7 0.7)
					(thickness 0.15)
				)
				(justify left bottom)
			)
		)
		(property "Datasheet" "https://www.coilcraft.com/getmedia/5e8de018-68c5-4442-84ce-d5212c44660c/1210poc.pdf"
			(at 0 0 90)
			(layer "F.Fab")
			(hide yes)
			(effects
				(font
					(size 1.27 1.27)
					(thickness 0.15)
				)
			)
		)
		(property "Description" "Power Inductor (SMT), 6.8 µH, 9.2 A, Shielded, 12.8 A, XAL7070"
			(at 0 0 90)
			(layer "F.Fab")
			(hide yes)
			(effects
				(font
					(size 1.27 1.27)
					(thickness 0.15)
				)
			)
		)
		(property "Author" "Antmicro"
			(at 193.548 -80.264 0)
			(layer "F.Fab")
			(hide yes)
			(effects
				(font
					(size 1 1)
					(thickness 0.15)
				)
			)
		)
		(property "IMax" "1.36 A"
			(at 193.548 -80.264 0)
			(layer "F.Fab")
			(hide yes)
			(effects
				(font
					(size 1 1)
					(thickness 0.15)
				)
			)
		)
		(property "ISat" "1 A"
			(at 193.548 -80.264 0)
			(layer "F.Fab")
			(hide yes)
			(effects
				(font
					(size 1 1)
					(thickness 0.15)
				)
			)
		)
		(property "License" "Apache-2.0"
			(at 193.548 -80.264 0)
			(layer "F.Fab")
			(hide yes)
			(effects
				(font
					(size 1 1)
					(thickness 0.15)
				)
			)
		)
		(property "MPN" "1210POC-682"
			(at 193.548 -80.264 0)
			(layer "F.Fab")
			(hide yes)
			(effects
				(font
					(size 1 1)
					(thickness 0.15)
				)
			)
		)
		(property "Manufacturer" "Coilcraft"
			(at 193.548 -80.264 0)
			(layer "F.Fab")
			(hide yes)
			(effects
				(font
					(size 1 1)
					(thickness 0.15)
				)
			)
		)
		(property "Size" "2.67x3.3"
			(at 193.548 -80.264 0)
			(layer "F.Fab")
			(hide yes)
			(effects
				(font
					(size 1 1)
					(thickness 0.15)
				)
			)
		)
		(property "Val" "6u8/1A"
			(at 193.548 -80.264 0)
			(layer "F.Fab")
			(hide yes)
			(effects
				(font
					(size 1 1)
					(thickness 0.15)
				)
			)
		)
		(sheetname "/Power/")
		(sheetfile "power.kicad_sch")
		(attr smd)
		(fp_line
			(start -0.7 -1.4)
			(end 0.7 -1.4)
			(stroke
				(width 0.15)
				(type solid)
			)
			(layer "F.SilkS")
		)
		(fp_line
			(start -0.7 1.4)
			(end 0.7 1.4)
			(stroke
				(width 0.15)
				(type solid)
			)
			(layer "F.SilkS")
		)
		(fp_rect
			(start -1.9 -1.585)
			(end 1.9 1.585)
			(stroke
				(width 0.05)
				(type solid)
			)
			(fill no)
			(layer "F.CrtYd")
		)
		(fp_line
			(start 1.65 -1.335)
			(end -1.65 -1.335)
			(stroke
				(width 0.15)
				(type solid)
			)
			(layer "F.Fab")
		)
		(fp_line
			(start 1.65 1.335)
			(end 1.65 -1.335)
			(stroke
				(width 0.15)
				(type solid)
			)
			(layer "F.Fab")
		)
		(fp_line
			(start 1.65 1.335)
			(end -1.65 1.335)
			(stroke
				(width 0.15)
				(type solid)
			)
			(layer "F.Fab")
		)
		(fp_line
			(start -1.65 1.335)
			(end -1.65 -1.335)
			(stroke
				(width 0.15)
				(type solid)
			)
			(layer "F.Fab")
		)
		(pad "1" smd rect
			(at -1.27 0 90)
			(size 0.65 2.65)
			(layers "F.Cu" "F.Mask" "F.Paste")
			(net 52 "Net-(L2-Pad2)")
			(pintype "passive")
		)
		(pad "2" smd rect
			(at 1.27 0 90)
			(size 0.65 2.65)
			(layers "F.Cu" "F.Mask" "F.Paste")
			(net 56 "Net-(L10-Pad1)")
			(pintype "passive")
		)
	)
	(footprint "antmicro-footprints:Conn_Molex_Nano-Fit_1x2_SMD_1054301202"
		(layer "F.Cu")
		(at 175.514 43.688 180)
		(descr "Molex Nano-Fit Power Connectors, 105430-xx02, 2 Pins per row")
		(tags "connector Molex Nano-Fit")
		(property "Reference" "J1"
			(at 2.604588 -5.512148 0)
			(layer "F.SilkS")
			(effects
				(font
					(size 0.7 0.7)
					(thickness 0.15)
				)
				(justify right bottom)
			)
		)
		(property "Value" "Molex_Nano-Fit_1x2_SMD_1054301202"
			(at 0 7.1 0)
			(layer "F.Fab")
			(effects
				(font
					(size 0.7 0.7)
					(thickness 0.15)
				)
				(justify right bottom)
			)
		)
		(property "Datasheet" "https://www.farnell.com/cad/3578051.pdf"
			(at 0 0 180)
			(layer "F.Fab")
			(hide yes)
			(effects
				(font
					(size 1.27 1.27)
					(thickness 0.15)
				)
			)
		)
		(property "Description" "Pin Header, Pitch 2.5 mm, 1 Row, 2 Contacts, Nano-Fit"
			(at 0 0 180)
			(layer "F.Fab")
			(hide yes)
			(effects
				(font
					(size 1.27 1.27)
					(thickness 0.15)
				)
			)
		)
		(property "Author" "Antmicro"
			(at 351.028 87.376 0)
			(layer "F.Fab")
			(hide yes)
			(effects
				(font
					(size 1 1)
					(thickness 0.15)
				)
			)
		)
		(property "License" "Apache-2.0"
			(at 351.028 87.376 0)
			(layer "F.Fab")
			(hide yes)
			(effects
				(font
					(size 1 1)
					(thickness 0.15)
				)
			)
		)
		(property "MPN" "105430-1202"
			(at 351.028 87.376 0)
			(layer "F.Fab")
			(hide yes)
			(effects
				(font
					(size 1 1)
					(thickness 0.15)
				)
			)
		)
		(property "Manufacturer" "Molex"
			(at 351.028 87.376 0)
			(layer "F.Fab")
			(hide yes)
			(effects
				(font
					(size 1 1)
					(thickness 0.15)
				)
			)
		)
		(sheetname "/Connectors/")
		(sheetfile "connectors.kicad_sch")
		(attr smd)
		(fp_line
			(start 4.48 2.298)
			(end 4.48 -4.5)
			(stroke
				(width 0.15)
				(type solid)
			)
			(layer "F.SilkS")
		)
		(fp_line
			(start 4.48 2.298)
			(end 4.28 2.698)
			(stroke
				(width 0.15)
				(type solid)
			)
			(layer "F.SilkS")
		)
		(fp_line
			(start 4.48 -4.5)
			(end 2.68 -4.5)
			(stroke
				(width 0.15)
				(type solid)
			)
			(layer "F.SilkS")
		)
		(fp_line
			(start 4.28 2.698)
			(end 4.28 4.299)
			(stroke
				(width 0.15)
				(type solid)
			)
			(layer "F.SilkS")
		)
		(fp_line
			(start -0.22 -4.5)
			(end 0.78 -4.5)
			(stroke
				(width 0.15)
				(type solid)
			)
			(layer "F.SilkS")
		)
		(fp_line
			(start -1.72 -4.5)
			(end -4.47 -4.5)
			(stroke
				(width 0.15)
				(type solid)
			)
			(layer "F.SilkS")
		)
		(fp_line
			(start -4.321 4.299)
			(end 4.28 4.299)
			(stroke
				(width 0.15)
				(type solid)
			)
			(layer "F.SilkS")
		)
		(fp_line
			(start -4.321 2.499)
			(end -4.321 4.299)
			(stroke
				(width 0.15)
				(type solid)
			)
			(layer "F.SilkS")
		)
		(fp_line
			(start -4.47 2.099)
			(end -4.321 2.499)
			(stroke
				(width 0.15)
				(type solid)
			)
			(layer "F.SilkS")
		)
		(fp_line
			(start -4.47 -4.5)
			(end -4.47 2.099)
			(stroke
				(width 0.15)
				(type solid)
			)
			(layer "F.SilkS")
		)
		(fp_circle
			(center 2.428 -4.91)
			(end 2.478 -4.91)
			(stroke
				(width 0.15)
				(type solid)
			)
			(fill yes)
			(layer "F.SilkS")
		)
		(fp_rect
			(start -4.77 -6.21)
			(end 4.77 6.11)
			(stroke
				(width 0.05)
				(type solid)
			)
			(fill no)
			(layer "F.CrtYd")
		)
		(pad "1" smd roundrect
			(at 1.528 -4.901 270)
			(size 2.5 1.24)
			(layers "F.Cu" "F.Mask" "F.Paste")
			(roundrect_rratio 0.25)
			(net 2 "/Connectors/DC_UNFUSED")
			(pintype "passive")
		)
		(pad "2" smd roundrect
			(at -0.97 -4.901 270)
			(size 2.5 1.24)
			(layers "F.Cu" "F.Mask" "F.Paste")
			(roundrect_rratio 0.25)
			(net 1 "GND")
			(pintype "passive")
		)
		(pad "MP" smd roundrect
			(at -3.54 0.029 180)
			(size 1.1 8.2)
			(layers "F.Cu" "F.Mask" "F.Paste")
			(roundrect_rratio 0.25)
			(net 1 "GND")
			(pintype "passive")
		)
		(pad "MP" smd roundrect
			(at 3.499 0.029 180)
			(size 1.1 8.2)
			(layers "F.Cu" "F.Mask" "F.Paste")
			(roundrect_rratio 0.25)
			(net 1 "GND")
			(pintype "passive")
		)
	)
	(footprint "antmicro-footprints:R_0402_1005Metric"
		(layer "F.Cu")
		(at 181.356 67.056)
		(descr "Resistor SMD 0402")
		(tags "resistor SMD 0402")
		(property "Reference" "R11"
			(at -1.279 9.2202 0)
			(layer "F.SilkS")
			(effects
				(font
					(size 0.7 0.7)
					(thickness 0.15)
				)
				(justify left bottom)
			)
		)
		(property "Value" "R_100R_0402"
			(at -1.011843 1.772047 0)
			(layer "F.Fab")
			(effects
				(font
					(size 0.7 0.7)
					(thickness 0.15)
				)
				(justify left bottom)
			)
		)
		(property "Datasheet" "https://www.bourns.com/docs/product-datasheets/cr.pdf"
			(at 0 0 0)
			(layer "F.Fab")
			(hide yes)
			(effects
				(font
					(size 1.27 1.27)
					(thickness 0.15)
				)
			)
		)
		(property "Description" "SMD Chip Resistor, 100 ohm, ± 1%, 62.5 mW, 0402 [1005 Metric], Thick Film, General Purpose"
			(at 0 0 0)
			(layer "F.Fab")
			(hide yes)
			(effects
				(font
					(size 1.27 1.27)
					(thickness 0.15)
				)
			)
		)
		(property "Author" "Antmicro"
			(at 0 0 0)
			(layer "F.Fab")
			(hide yes)
			(effects
				(font
					(size 1 1)
					(thickness 0.15)
				)
			)
		)
		(property "License" "Apache-2.0"
			(at 0 0 0)
			(layer "F.Fab")
			(hide yes)
			(effects
				(font
					(size 1 1)
					(thickness 0.15)
				)
			)
		)
		(property "MPN" "CR0402-FX-1000GLF"
			(at 0 0 0)
			(layer "F.Fab")
			(hide yes)
			(effects
				(font
					(size 1 1)
					(thickness 0.15)
				)
			)
		)
		(property "Manufacturer" "Bourns"
			(at 0 0 0)
			(layer "F.Fab")
			(hide yes)
			(effects
				(font
					(size 1 1)
					(thickness 0.15)
				)
			)
		)
		(property "Tolerance" "1%"
			(at 0 0 0)
			(layer "F.Fab")
			(hide yes)
			(effects
				(font
					(size 1 1)
					(thickness 0.15)
				)
			)
		)
		(property "Val" "100R"
			(at 0 0 0)
			(layer "F.Fab")
			(hide yes)
			(effects
				(font
					(size 1 1)
					(thickness 0.15)
				)
			)
		)
		(sheetname "/Connectors/")
		(sheetfile "connectors.kicad_sch")
		(attr smd)
		(fp_rect
			(start -0.925 -0.47)
			(end 0.925 0.47)
			(stroke
				(width 0.05)
				(type default)
			)
			(fill no)
			(layer "F.CrtYd")
		)
		(fp_rect
			(start -0.5 -0.25)
			(end 0.5 0.25)
			(stroke
				(width 0.15)
				(type solid)
			)
			(fill no)
			(layer "F.Fab")
		)
		(pad "1" smd roundrect
			(at -0.48 0)
			(size 0.59 0.64)
			(layers "F.Cu" "F.Mask" "F.Paste")
			(roundrect_rratio 0.25)
			(net 44 "/Connectors/SDA_CAM")
			(pintype "passive")
		)
		(pad "2" smd roundrect
			(at 0.48 0)
			(size 0.59 0.64)
			(layers "F.Cu" "F.Mask" "F.Paste")
			(roundrect_rratio 0.25)
			(net 119 "/Connectors/SDA_CAM0")
			(pintype "passive")
		)
	)
	(footprint "antmicro-footprints:LED_0603_1608Metric_G"
		(layer "F.Cu")
		(at 144.776 96.1 90)
		(descr "LED SMD 0603 Green")
		(tags "LED SMD 0603 Green")
		(property "Reference" "D20"
			(at 6.343331 -26.359333 180)
			(layer "F.SilkS")
			(effects
				(font
					(size 0.7 0.7)
					(thickness 0.15)
				)
				(justify right bottom)
			)
		)
		(property "Value" "LED_G_0603_LTST-C190GKT"
			(at -0.001 1.599 90)
			(layer "F.Fab")
			(effects
				(font
					(size 0.7 0.7)
					(thickness 0.15)
				)
				(justify left bottom)
			)
		)
		(property "Datasheet" "https://media.digikey.com/pdf/Data%20Sheets/Lite-On%20PDFs/LTST-C190GKT.pdf"
			(at 0 0 90)
			(layer "F.Fab")
			(hide yes)
			(effects
				(font
					(size 1.27 1.27)
					(thickness 0.15)
				)
			)
		)
		(property "Description" "LED, Green, SMD, 0603, 20 mA, 2.1 V, 569 nm"
			(at 0 0 90)
			(layer "F.Fab")
			(hide yes)
			(effects
				(font
					(size 1.27 1.27)
					(thickness 0.15)
				)
			)
		)
		(property "Author" "Antmicro"
			(at 240.876 -48.676 0)
			(layer "F.Fab")
			(hide yes)
			(effects
				(font
					(size 1 1)
					(thickness 0.15)
				)
			)
		)
		(property "Color" "Green"
			(at 240.876 -48.676 0)
			(layer "F.Fab")
			(hide yes)
			(effects
				(font
					(size 1 1)
					(thickness 0.15)
				)
			)
		)
		(property "License" "Apache-2.0"
			(at 240.876 -48.676 0)
			(layer "F.Fab")
			(hide yes)
			(effects
				(font
					(size 1 1)
					(thickness 0.15)
				)
			)
		)
		(property "MPN" "LTST-C190GKT"
			(at 240.876 -48.676 0)
			(layer "F.Fab")
			(hide yes)
			(effects
				(font
					(size 1 1)
					(thickness 0.15)
				)
			)
		)
		(property "Manufacturer" "Lite-On"
			(at 240.876 -48.676 0)
			(layer "F.Fab")
			(hide yes)
			(effects
				(font
					(size 1 1)
					(thickness 0.15)
				)
			)
		)
		(property "VSD_class" "LED"
			(at 240.876 -48.676 0)
			(layer "F.Fab")
			(hide yes)
			(effects
				(font
					(size 1 1)
					(thickness 0.15)
				)
			)
		)
		(sheetname "/Power/")
		(sheetfile "power.kicad_sch")
		(attr smd)
		(fp_line
			(start 0.22 -0.35)
			(end -0.22 -0.35)
			(stroke
				(width 0.15)
				(type solid)
			)
			(layer "F.SilkS")
		)
		(fp_line
			(start -1.18 -0.319)
			(end -1.18 0.321)
			(stroke
				(width 0.15)
				(type solid)
			)
			(layer "F.SilkS")
		)
		(fp_line
			(start 0.105328 0.001008)
			(end 0.24 0.001)
			(stroke
				(width 0.1)
				(type solid)
			)
			(layer "F.SilkS")
		)
		(fp_line
			(start -0.094672 0.001008)
			(end 0.105328 -0.198992)
			(stroke
				(width 0.1)
				(type solid)
			)
			(layer "F.SilkS")
		)
		(fp_line
			(start -0.094672 0.001008)
			(end -0.24 0.001008)
			(stroke
				(width 0.1)
				(type solid)
			)
			(layer "F.SilkS")
		)
		(fp_line
			(start 0.105328 0.201008)
			(end 0.105328 -0.198992)
			(stroke
				(width 0.1)
				(type solid)
			)
			(layer "F.SilkS")
		)
		(fp_line
			(start 0.105328 0.201008)
			(end -0.094672 0.001008)
			(stroke
				(width 0.1)
				(type solid)
			)
			(layer "F.SilkS")
		)
		(fp_line
			(start -0.094672 0.201008)
			(end -0.094672 -0.198992)
			(stroke
				(width 0.1)
				(type solid)
			)
			(layer "F.SilkS")
		)
		(fp_line
			(start 0.22 0.35)
			(end -0.22 0.35)
			(stroke
				(width 0.15)
				(type solid)
			)
			(layer "F.SilkS")
		)
		(fp_rect
			(start 1.25 0.65)
			(end -1.25 -0.65)
			(stroke
				(width 0.05)
				(type solid)
			)
			(fill no)
			(layer "F.CrtYd")
		)
		(fp_line
			(start 0.201 -0.202)
			(end -0.101 0)
			(stroke
				(width 0.15)
				(type solid)
			)
			(layer "F.Fab")
		)
		(fp_line
			(start -0.199 -0.202)
			(end -0.199 0.1)
			(stroke
				(width 0.15)
				(type solid)
			)
			(layer "F.Fab")
		)
		(fp_line
			(start 0.599 0)
			(end 0.201 0)
			(stroke
				(width 0.15)
				(type solid)
			)
			(layer "F.Fab")
		)
		(fp_line
			(start 0.201 0)
			(end 0.201 -0.202)
			(stroke
				(width 0.15)
				(type solid)
			)
			(layer "F.Fab")
		)
		(fp_line
			(start -0.101 0)
			(end 0.201 0.2)
			(stroke
				(width 0.15)
				(type solid)
			)
			(layer "F.Fab")
		)
		(fp_line
			(start -0.199 0)
			(end -0.597 0)
			(stroke
				(width 0.15)
				(type solid)
			)
			(layer "F.Fab")
		)
		(fp_line
			(start 0.201 0.2)
			(end 0.201 0)
			(stroke
				(width 0.15)
				(type solid)
			)
			(layer "F.Fab")
		)
		(fp_line
			(start -0.199 0.2)
			(end -0.199 0.1)
			(stroke
				(width 0.15)
				(type solid)
			)
			(layer "F.Fab")
		)
		(fp_rect
			(start 0.848 0.4)
			(end -0.85 -0.402)
			(stroke
				(width 0.15)
				(type solid)
			)
			(fill no)
			(layer "F.Fab")
		)
		(pad "1" smd roundrect
			(at -0.7 0 270)
			(size 0.8 1)
			(layers "F.Cu" "F.Mask" "F.Paste")
			(roundrect_rratio 0.2)
			(net 145 "Net-(D20-C)")
			(pinfunction "C")
			(pintype "passive")
		)
		(pad "2" smd roundrect
			(at 0.7 0 270)
			(size 0.8 1)
			(layers "F.Cu" "F.Mask" "F.Paste")
			(roundrect_rratio 0.2)
			(net 147 "Net-(D20-A)")
			(pinfunction "A")
			(pintype "passive")
		)
	)
)
